# TIMECARD (Time Appliance Project (Time Card)) — schematic netlist excerpt (pin names and nets, part order shuffled) for the footprints in the layout excerpt that follows; sources: Cadence DE-HDL packaged netlist, KiCad conversion of R4006-B0001-02_R01.brd

C10  CAPACITOR  10UF 25V 20%  pkg SMC_0805R_H057  page 27 : \1\ = XP12R0V ; \2\ = SG

(kicad_pcb
	(version 20260206)
	(generator "pcbnew")
	(generator_version "10.0")
	(general
		(thickness 1.6)
		(legacy_teardrops no)
	)
	(paper "A4")
	(title_block
		(title "timecard-production-celestica-r4006 — R4006-B0001-02_R01.brd")
		(comment 1 "Time Appliance Project (Time Card) / footprints 299-299 of 1113")
	)
	(layers
		(0 "F.Cu" signal "TOP")
		(4 "In1.Cu" signal "L02_GND1")
		(6 "In2.Cu" signal "L03_SIG1")
		(8 "In3.Cu" signal "L04_GND2")
		(10 "In4.Cu" signal "L05_VCC1")
		(12 "In5.Cu" signal "L06_VCC2")
		(14 "In6.Cu" signal "L07_GND3")
		(16 "In7.Cu" signal "L08_SIG2")
		(18 "In8.Cu" signal "L09_GND4")
		(2 "B.Cu" signal "BOTTOM")
		(9 "F.Adhes" user "F.Adhesive")
		(11 "B.Adhes" user "B.Adhesive")
		(13 "F.Paste" user "Package Geometry/Pastemask Top")
		(15 "B.Paste" user "Package Geometry/Pastemask Bottom")
		(5 "F.SilkS" user "Ref Des/Silkscreen Top")
		(7 "B.SilkS" user "Ref Des/Silkscreen Bottom")
		(1 "F.Mask" user "Board Geometry/Soldermask Top")
		(3 "B.Mask" user "Board Geometry/Soldermask Bottom")
		(17 "Dwgs.User" user "User.Drawings")
		(19 "Cmts.User" user "User.Comments")
		(21 "Eco1.User" user "User.Eco1")
		(23 "Eco2.User" user "User.Eco2")
		(25 "Edge.Cuts" user "Board Geometry/Outline")
		(27 "Margin" user)
		(31 "F.CrtYd" user "Package Geometry/Place Bound Top")
		(29 "B.CrtYd" user "Package Geometry/Place Bound Bottom")
		(35 "F.Fab" user "Ref Des/Assembly Top")
		(33 "B.Fab" user "Ref Des/Assembly Bottom")
	)
	(footprint ""
		(layer "F.Cu")
		(at 133.4516 -94.107 90)
		(property "Reference" "C10"
			(at -2.921 0.44577 90)
			(unlocked yes)
			(layer "F.SilkS")
			(effects
				(font
					(size 0.7874 0.5842)
					(thickness 0.1524)
				)
			)
		)
		(property "Value" "VAL*"
			(at 0.0762 3.134106 90)
			(unlocked yes)
			(layer "F.Fab")
			(hide yes)
			(effects
				(font
					(size 0.7874 0.5842)
					(thickness 0.1524)
				)
			)
		)
		(property "Device Type" "CAPACITOR-G107-0F106-EM,10UF,2A"
			(at 0.0508 2.194306 90)
			(unlocked yes)
			(layer "F.Fab")
			(hide yes)
			(effects
				(font
					(size 0.7874 0.5842)
					(thickness 0.1524)
				)
			)
		)
		(property "User Part Number" "PARTNUM*"
			(at 0.1016 5.013706 90)
			(unlocked yes)
			(layer "Cmts.User")
			(hide yes)
			(effects
				(font
					(size 0.7874 0.5842)
					(thickness 0.1524)
				)
			)
		)
		(property "Tolerance" "TOL*"
			(at 0.0762 4.048506 90)
			(unlocked yes)
			(layer "Cmts.User")
			(hide yes)
			(effects
				(font
					(size 0.7874 0.5842)
					(thickness 0.1524)
				)
			)
		)
		(duplicate_pad_numbers_are_jumpers no)
		(fp_line
			(start 1.5748 -0.9398)
			(end -1.5748 -0.9398)
			(stroke
				(width 0.1)
				(type default)
			)
			(layer "F.SilkS")
		)
		(fp_line
			(start -1.5748 -0.9398)
			(end -1.5748 0.9398)
			(stroke
				(width 0.1)
				(type default)
			)
			(layer "F.SilkS")
		)
		(fp_line
			(start 1.5748 0.9398)
			(end 1.5748 -0.9398)
			(stroke
				(width 0.1)
				(type default)
			)
			(layer "F.SilkS")
		)
		(fp_line
			(start -1.5748 0.9398)
			(end 1.5748 0.9398)
			(stroke
				(width 0.1)
				(type default)
			)
			(layer "F.SilkS")
		)
		(fp_rect
			(start -1.5748 -0.9398)
			(end 1.5748 0.9398)
			(stroke
				(width 0)
				(type default)
			)
			(fill no)
			(layer "F.CrtYd")
		)
		(fp_line
			(start 1.016 -0.635)
			(end -1.016 -0.635)
			(stroke
				(width 0.1)
				(type default)
			)
			(layer "F.Fab")
		)
		(fp_line
			(start -1.016 -0.635)
			(end -1.016 0.635)
			(stroke
				(width 0.1)
				(type default)
			)
			(layer "F.Fab")
		)
		(fp_line
			(start 1.016 0.635)
			(end 1.016 -0.635)
			(stroke
				(width 0.1)
				(type default)
			)
			(layer "F.Fab")
		)
		(fp_line
			(start -1.016 0.635)
			(end 1.016 0.635)
			(stroke
				(width 0.1)
				(type default)
			)
			(layer "F.Fab")
		)
		(pad "1" smd rect
			(at -0.8382 0 90)
			(size 0.9652 1.3716)
			(layers "F.Cu" "F.Mask" "F.Paste")
			(net "XP12R0V")
		)
		(pad "2" smd rect
			(at 0.8382 0 90)
			(size 0.9652 1.3716)
			(layers "F.Cu" "F.Mask" "F.Paste")
			(net "SG")
		)
		(zone
			(layer "F.Cu")
			(hatch none 0.5)
			(connect_pads
				(clearance 0)
			)
			(min_thickness 0.25)
			(keepout
				(tracks allowed)
				(vias not_allowed)
				(pads allowed)
				(copperpour not_allowed)
				(footprints allowed)
			)
			(placement
				(enabled no)
				(sheetname "")
			)
			(fill
				(thermal_gap 0.5)
				(thermal_bridge_width 0.5)
				(island_removal_mode 0)
			)
			(polygon
				(pts
					(xy 132.8166 -93.8784) (xy 134.0866 -93.8784) (xy 134.0866 -94.3356) (xy 132.8166 -94.3356)
				)
			)
		)
	)
)
